FILE_TYPE = CONNECTIVITY;
{Allegro Design Entry HDL 17.4-2019 S026 (4007227) 1/17/2022}
"PAGE_NUMBER" = 23;
0"NC";
1"P5E_CPU0_G3_TX_DP<15:0>";
2"P5E_CPU0_G3_TX_DN<15:0>";
3"P5E_CPU0_G3_RX_DP<15:0>";
4"GMI_CPU0_G2_CPU1_G0_TX_DN<15:0>";
5"GMI_CPU1_G0_CPU0_G2_TX_DN<15:0>";
6"GMI_CPU1_G0_CPU0_G2_TX_DP<15:0>";
7"P5E_CPU0_G3_RX_DN<15:0>";
8"GMI_CPU0_G2_CPU1_G0_TX_DP<15:0>";
9"P5E_CPU0_G3_TX_DN<2>";
10"P5E_CPU0_G3_TX_DP<3>";
11"GMI_CPU1_G0_CPU0_G2_TX_DN<5>";
12"GMI_CPU1_G0_CPU0_G2_TX_DP<6>";
13"GMI_CPU1_G0_CPU0_G2_TX_DN<6>";
14"GMI_CPU1_G0_CPU0_G2_TX_DP<7>";
15"GMI_CPU1_G0_CPU0_G2_TX_DN<7>";
16"GMI_CPU1_G0_CPU0_G2_TX_DP<8>";
17"GMI_CPU1_G0_CPU0_G2_TX_DN<8>";
18"GMI_CPU1_G0_CPU0_G2_TX_DP<9>";
19"GMI_CPU1_G0_CPU0_G2_TX_DN<9>";
20"GMI_CPU1_G0_CPU0_G2_TX_DP<11>";
21"GMI_CPU1_G0_CPU0_G2_TX_DN<11>";
22"GMI_CPU1_G0_CPU0_G2_TX_DP<12>";
23"GMI_CPU1_G0_CPU0_G2_TX_DN<12>";
24"GMI_CPU1_G0_CPU0_G2_TX_DP<13>";
25"P5E_CPU0_G3_RX_DP<7>";
26"P5E_CPU0_G3_RX_DN<7>";
27"P5E_CPU0_G3_RX_DP<9>";
28"P5E_CPU0_G3_RX_DP<12>";
29"P5E_CPU0_G3_RX_DP<13>";
30"P5E_CPU0_G3_RX_DN<12>";
31"P5E_CPU0_G3_RX_DN<13>";
32"P5E_CPU0_G3_RX_DP<14>";
33"P5E_CPU0_G3_RX_DN<14>";
34"P5E_CPU0_G3_RX_DP<15>";
35"P5E_CPU0_G3_RX_DN<15>";
36"P5E_CPU0_G3_RX_DP<10>";
37"P5E_CPU0_G3_RX_DN<10>";
38"P5E_CPU0_G3_RX_DP<11>";
39"GMI_CPU1_G0_CPU0_G2_TX_DN<4>";
40"GMI_CPU1_G0_CPU0_G2_TX_DN<3>";
41"GMI_CPU1_G0_CPU0_G2_TX_DP<5>";
42"GMI_CPU1_G0_CPU0_G2_TX_DN<2>";
43"GMI_CPU1_G0_CPU0_G2_TX_DP<4>";
44"GMI_CPU1_G0_CPU0_G2_TX_DN<1>";
45"GMI_CPU1_G0_CPU0_G2_TX_DP<3>";
46"GMI_CPU1_G0_CPU0_G2_TX_DN<0>";
47"GMI_CPU1_G0_CPU0_G2_TX_DP<2>";
48"GMI_CPU1_G0_CPU0_G2_TX_DP<1>";
49"GMI_CPU1_G0_CPU0_G2_TX_DP<0>";
50"GMI_CPU1_G0_CPU0_G2_TX_DN<15>";
51"GMI_CPU1_G0_CPU0_G2_TX_DP<15>";
52"GMI_CPU1_G0_CPU0_G2_TX_DN<13>";
53"GMI_CPU1_G0_CPU0_G2_TX_DN<14>";
54"GMI_CPU1_G0_CPU0_G2_TX_DP<14>";
55"P5E_CPU0_G3_TX_DP<15>";
56"P5E_CPU0_G3_TX_DP<12>";
57"P5E_CPU0_G3_TX_DP<14>";
58"P5E_CPU0_G3_TX_DP<11>";
59"P5E_CPU0_G3_TX_DP<13>";
60"P5E_CPU0_G3_TX_DN<9>";
61"P5E_CPU0_G3_TX_DN<13>";
62"P5E_CPU0_G3_TX_DN<12>";
63"P5E_CPU0_G3_TX_DN<15>";
64"P5E_CPU0_G3_TX_DN<11>";
65"P5E_CPU0_G3_TX_DN<14>";
66"P5E_CPU0_G3_TX_DP<8>";
67"P5E_CPU0_G3_TX_DN<8>";
68"GMI_CPU0_G2_CPU1_G0_TX_DP<15>";
69"GMI_CPU0_G2_CPU1_G0_TX_DP<13>";
70"GMI_CPU0_G2_CPU1_G0_TX_DP<14>";
71"GMI_CPU0_G2_CPU1_G0_TX_DP<11>";
72"GMI_CPU0_G2_CPU1_G0_TX_DP<9>";
73"GMI_CPU0_G2_CPU1_G0_TX_DP<12>";
74"GMI_CPU0_G2_CPU1_G0_TX_DP<10>";
75"GMI_CPU0_G2_CPU1_G0_TX_DP<8>";
76"GMI_CPU0_G2_CPU1_G0_TX_DP<7>";
77"GMI_CPU0_G2_CPU1_G0_TX_DP<6>";
78"GMI_CPU0_G2_CPU1_G0_TX_DP<5>";
79"GMI_CPU0_G2_CPU1_G0_TX_DP<4>";
80"GMI_CPU0_G2_CPU1_G0_TX_DP<3>";
81"GMI_CPU0_G2_CPU1_G0_TX_DP<2>";
82"GMI_CPU0_G2_CPU1_G0_TX_DP<0>";
83"GMI_CPU0_G2_CPU1_G0_TX_DP<1>";
84"GMI_CPU0_G2_CPU1_G0_TX_DN<7>";
85"GMI_CPU0_G2_CPU1_G0_TX_DN<6>";
86"GMI_CPU0_G2_CPU1_G0_TX_DN<5>";
87"GMI_CPU0_G2_CPU1_G0_TX_DN<4>";
88"GMI_CPU0_G2_CPU1_G0_TX_DN<3>";
89"GMI_CPU0_G2_CPU1_G0_TX_DN<2>";
90"GMI_CPU0_G2_CPU1_G0_TX_DN<1>";
91"GMI_CPU0_G2_CPU1_G0_TX_DN<0>";
92"GMI_CPU0_G2_CPU1_G0_TX_DN<13>";
93"GMI_CPU0_G2_CPU1_G0_TX_DN<11>";
94"GMI_CPU0_G2_CPU1_G0_TX_DN<9>";
95"GMI_CPU0_G2_CPU1_G0_TX_DN<14>";
96"GMI_CPU0_G2_CPU1_G0_TX_DN<12>";
97"GMI_CPU0_G2_CPU1_G0_TX_DN<10>";
98"GMI_CPU0_G2_CPU1_G0_TX_DN<8>";
99"P5E_CPU0_G3_RX_DN<11>";
100"P5E_CPU0_G3_RX_DN<9>";
101"P5E_CPU0_G3_RX_DN<8>";
102"P5E_CPU0_G3_RX_DN<0>";
103"P5E_CPU0_G3_RX_DP<1>";
104"P5E_CPU0_G3_RX_DN<1>";
105"P5E_CPU0_G3_RX_DP<2>";
106"P5E_CPU0_G3_RX_DN<2>";
107"P5E_CPU0_G3_RX_DP<3>";
108"P5E_CPU0_G3_RX_DN<3>";
109"P5E_CPU0_G3_RX_DP<6>";
110"P5E_CPU0_G3_RX_DN<6>";
111"P5E_CPU0_G3_RX_DP<0>";
112"P5E_CPU0_G3_RX_DN<5>";
113"P5E_CPU0_G3_RX_DP<4>";
114"P5E_CPU0_G3_RX_DN<4>";
115"P5E_CPU0_G3_RX_DP<5>";
116"P5E_CPU0_G3_TX_DP<1>";
117"GMI_CPU1_G0_CPU0_G2_TX_DP<10>";
118"GMI_CPU1_G0_CPU0_G2_TX_DN<10>";
119"GMI_CPU0_G2_CPU1_G0_TX_DN<15>";
120"P5E_CPU0_G3_TX_DP<9>";
121"P5E_CPU0_G3_TX_DP<7>";
122"P5E_CPU0_G3_TX_DP<2>";
123"P5E_CPU0_G3_TX_DN<7>";
124"P5E_CPU0_G3_RX_DP<8>";
125"P5E_CPU0_G3_TX_DP<10>";
126"P5E_CPU0_G3_TX_DN<10>";
127"P5E_CPU0_G3_TX_DN<6>";
128"P5E_CPU0_G3_TX_DP<5>";
129"P5E_CPU0_G3_TX_DN<5>";
130"P5E_CPU0_G3_TX_DP<6>";
131"P5E_CPU0_G3_TX_DN<4>";
132"P5E_CPU0_G3_TX_DP<4>";
133"P5E_CPU0_G3_TX_DN<3>";
134"P5E_CPU0_G3_TX_DN<1>";
135"P5E_CPU0_G3_TX_DN<0>";
136"P5E_CPU0_G3_TX_DP<0>";
%"GENOA_SP5"
"13","(-4775,5075)","0","pure_quanta","I215";
;
LOCATION"U25"
$SEC"13"
CDS_SEC"13"
PART_TYPE"SMLF"
VALUE"SOCKET6096_13568-001"
MATERIAL"IO"
CDS_LIB"pure_quanta"
NEEDS_NO_SIZE"TRUE"
CDS_LMAN_SYM_OUTLINE"-1100,950,1100,-950"
PART_NUMBER"DGA^6000030";
"G2_TXP0"
$PN"N23"82;
"G2_RXN7"
$PN"AC29"15;
"G2_RXN6"
$PN"AE29"13;
"G2_RXN5"
$PN"AG26"11;
"G2_RXP7"
$PN"AC30"14;
"G2_TXN7"
$PN"J30"84;
"G2_RXN4"
$PN"AC26"39;
"G2_RXP6"
$PN"AE30"12;
"G2_TXN6"
$PN"L27"85;
"G2_RXN3"
$PN"AE26"40;
"G2_RXP5"
$PN"AG27"41;
"G2_TXN5"
$PN"G27"86;
"G2_TXP7"
$PN"J29"76;
"G2_RXN2"
$PN"AG23"42;
"G2_RXP4"
$PN"AC27"43;
"G2_TXN4"
$PN"J27"87;
"G2_TXP6"
$PN"L26"77;
"G2_RXN1"
$PN"AC23"44;
"G2_RXP3"
$PN"AE27"45;
"G2_TXN3"
$PN"L24"88;
"G2_TXP5"
$PN"G26"78;
"G2_RXN0"
$PN"AE23"46;
"G2_RXP2"
$PN"AG24"47;
"G2_TXN2"
$PN"G24"89;
"G2_TXP4"
$PN"J26"79;
"G2_RXP1"
$PN"AC24"48;
"G2_TXN1"
$PN"J24"90;
"G2_TXP3"
$PN"L23"80;
"G2_RXP0"
$PN"AE24"49;
"G2_TXN0"
$PN"N24"91;
"G2_TXP2"
$PN"G23"81;
"G2_TXP1"
$PN"J23"83;
"G2_RXN15"
$PN"AF35"50;
"G2_RXP15"
$PN"AF36"51;
"G2_RXN13"
$PN"AB35"52;
"G2_RXP13"
$PN"AB36"24;
"G2_RXN11"
$PN"AA32"21;
"G2_RXP11"
$PN"AA33"20;
"G2_RXN9"
$PN"AE32"19;
"G2_RXP9"
$PN"AE33"18;
"G2_RXN14"
$PN"AD35"53;
"G2_RXP14"
$PN"AD36"54;
"G2_RXN12"
$PN"AG32"23;
"G2_RXP12"
$PN"AG33"22;
"G2_RXN10"
$PN"AC32"118;
"G2_RXP10"
$PN"AC33"117;
"G2_RXN8"
$PN"AG29"17;
"G2_RXP8"
$PN"AG30"16;
"G2_TXN15"
$PN"M36"119;
"G2_TXP15"
$PN"M35"68;
"G2_TXN13"
$PN"H36"92;
"G2_TXP13"
$PN"H35"69;
"G2_TXN11"
$PN"G33"93;
"G2_TXP11"
$PN"G32"71;
"G2_TXN9"
$PN"L30"94;
"G2_TXP9"
$PN"L29"72;
"G2_TXN14"
$PN"K36"95;
"G2_TXP14"
$PN"K35"70;
"G2_TXN12"
$PN"L33"96;
"G2_TXP12"
$PN"L32"73;
"G2_TXN10"
$PN"J33"97;
"G2_TXP10"
$PN"J32"74;
"G2_TXN8"
$PN"G30"98;
"G2_TXP8"
$PN"G29"75;
%"GENOA_SP5"
"14","(-4750,2200)","0","pure_quanta","I216";
;
LOCATION"U25"
$SEC"14"
CDS_SEC"14"
PART_TYPE"SMLF"
MATERIAL"IO"
VALUE"SOCKET6096_13568-001"
CDS_LIB"pure_quanta"
NEEDS_NO_SIZE"TRUE"
CDS_LMAN_SYM_OUTLINE"-1100,950,1100,-950"
PART_NUMBER"DGA^6000030";
"G3_RXN2||SATA22_RXN"
$PN"AN23"106;
"G3_TXN9||SATA31_TXN"
$PN"U30"60;
"G3_RXN12||SATA34_RXN"
$PN"AK35"30;
"G3_RXN15||SATA37_RXN"
$PN"AP35"35;
"G3_TXP5||SATA25_TXP"
$PN"N26"128;
"G3_RXN9||SATA31_RXN"
$PN"AL32"100;
"G3_TXP2||SATA22_TXP"
$PN"W23"122;
"G3_RXP2||SATA22_RXP"
$PN"AN24"105;
"G3_RXP5||SATA25_RXP"
$PN"AN27"115;
"G3_RXP14||SATA36_RXP"
$PN"AM36"32;
"G3_TXN4||SATA24_TXN"
$PN"R27"131;
"G3_TXN7||SATA27_TXN"
$PN"R30"123;
"G3_TXN10||SATA32_TXN"
$PN"R33"126;
"G3_TXN13||SATA35_TXN"
$PN"P36"61;
"G3_RXP11||SATA33_RXP"
$PN"AN33"38;
"G3_TXN1||SATA21_TXN"
$PN"R24"134;
"G3_TXP9||SATA31_TXP"
$PN"U29"120;
"G3_TXP15||SATA37_TXP"
$PN"V35"55;
"G3_RXN1||SATA21_RXN"
$PN"AJ23"104;
"G3_RXN4||SATA24_RXN"
$PN"AJ26"114;
"G3_RXN7||SATA27_RXN"
$PN"AJ29"26;
"G3_TXP12||SATA34_TXP"
$PN"U32"56;
"G3_RXP9||SATA31_RXP"
$PN"AL33"27;
"G3_TXP7||SATA27_TXP"
$PN"R29"121;
"G3_TXN8||SATA30_TXN"
$PN"N30"67;
"G3_RXN11||SATA33_RXN"
$PN"AN32"99;
"G3_RXN14||SATA36_RXN"
$PN"AM35"33;
"G3_TXP1||SATA21_TXP"
$PN"R23"116;
"G3_TXP4||SATA24_TXP"
$PN"R26"132;
"G3_RXP7||SATA27_RXP"
$PN"AJ30"25;
"G3_RXN8||SATA30_RXN"
$PN"AN29"101;
"G3_TXN12||SATA34_TXN"
$PN"U33"62;
"G3_TXN15||SATA37_TXN"
$PN"V36"63;
"G3_RXP1||SATA21_RXP"
$PN"AJ24"103;
"G3_RXP4||SATA24_RXP"
$PN"AJ27"113;
"G3_RXP10||SATA32_RXP"
$PN"AJ33"36;
"G3_RXP13||SATA35_RXP"
$PN"AH36"29;
"G3_TXN3||SATA23_TXN"
$PN"U27"133;
"G3_TXN6||SATA26_TXN"
$PN"W27"127;
"G3_RXN6||SATA26_RXN"
$PN"AL29"110;
"G3_TXN0||SATA20_TXN"
$PN"U24"135;
"G3_TXP8||SATA30_TXP"
$PN"N29"66;
"G3_TXP14||SATA36_TXP"
$PN"T35"57;
"G3_RXN0||SATA20_RXN"
$PN"AL23"102;
"G3_RXN3||SATA23_RXN"
$PN"AL26"108;
"G3_RXP8||SATA30_RXP"
$PN"AN30"124;
"G3_TXP11||SATA33_TXP"
$PN"N32"58;
"G3_RXN13||SATA35_RXN"
$PN"AH35"31;
"G3_TXP6||SATA26_TXP"
$PN"W26"130;
"G3_RXN10||SATA32_RXN"
$PN"AJ32"37;
"G3_TXP0||SATA20_TXP"
$PN"U23"136;
"G3_TXP3||SATA23_TXP"
$PN"U26"10;
"G3_RXP3||SATA23_RXP"
$PN"AL27"107;
"G3_RXP6||SATA26_RXP"
$PN"AL30"109;
"G3_RXP15||SATA37_RXP"
$PN"AP36"34;
"G3_TXN5||SATA25_TXN"
$PN"N27"129;
"G3_TXN11||SATA33_TXN"
$PN"N33"64;
"G3_TXN14||SATA36_TXN"
$PN"T36"65;
"G3_RXP0||SATA20_RXP"
$PN"AL24"111;
"G3_RXP12||SATA34_RXP"
$PN"AK36"28;
"G3_TXN2||SATA22_TXN"
$PN"W24"9;
"G3_RXN5||SATA25_RXN"
$PN"AN26"112;
"G3_TXP10||SATA32_TXP"
$PN"R32"125;
"G3_TXP13||SATA35_TXP"
$PN"P35"59;
%"TAP"
"6","(-2950,5775)","2","mstr_standard","I219";
;
BOM_COST"IO_SLOT"
CDS_LIB"mstr_standard"
ROOM"RISER1"
BODY_TYPE"PLUMBING"
HDL_TAP"TRUE";
"B \NAC \NWC"4;
"S \NAC"
BN"0"91;
%"TAP"
"6","(-2950,5675)","2","mstr_standard","I220";
;
CDS_LIB"mstr_standard"
BOM_COST"IO_SLOT"
ROOM"RISER1"
BODY_TYPE"PLUMBING"
HDL_TAP"TRUE";
"B \NAC \NWC"4;
"S \NAC"
BN"1"90;
%"TAP"
"6","(-3100,5825)","2","mstr_standard","I221";
;
CDS_LIB"mstr_standard"
BOM_COST"IO_SLOT"
ROOM"RISER1"
BODY_TYPE"PLUMBING"
HDL_TAP"TRUE";
"B \NAC \NWC"8;
"S \NAC"
BN"0"82;
%"TAP"
"6","(-3100,5725)","2","mstr_standard","I222";
;
CDS_LIB"mstr_standard"
BOM_COST"IO_SLOT"
ROOM"RISER1"
BODY_TYPE"PLUMBING"
HDL_TAP"TRUE";
"B \NAC \NWC"8;
"S \NAC"
BN"1"83;
%"TAP"
"6","(-2950,5575)","2","standard","I223";
;
CDS_LIB"standard"
BOM_COST"IO_SLOT"
ROOM"RISER1"
BODY_TYPE"PLUMBING"
HDL_TAP"TRUE";
"B \NAC \NWC"4;
"S \NAC"
BN"2"89;
%"TAP"
"6","(-2950,5475)","2","standard","I224";
;
CDS_LIB"standard"
BOM_COST"IO_SLOT"
ROOM"RISER1"
BODY_TYPE"PLUMBING"
HDL_TAP"TRUE";
"B \NAC \NWC"4;
"S \NAC"
BN"3"88;
%"TAP"
"6","(-3100,5625)","2","standard","I225";
;
CDS_LIB"standard"
BOM_COST"IO_SLOT"
ROOM"RISER1"
BODY_TYPE"PLUMBING"
HDL_TAP"TRUE";
"B \NAC \NWC"8;
"S \NAC"
BN"2"81;
%"TAP"
"6","(-3100,5525)","2","standard","I226";
;
CDS_LIB"standard"
BOM_COST"IO_SLOT"
ROOM"RISER1"
BODY_TYPE"PLUMBING"
HDL_TAP"TRUE";
"B \NAC \NWC"8;
"S \NAC"
BN"3"80;
%"TAP"
"6","(-3100,5425)","2","standard","I227";
;
CDS_LIB"standard"
BOM_COST"IO_SLOT"
ROOM"RISER1"
BODY_TYPE"PLUMBING"
HDL_TAP"TRUE";
"B \NAC \NWC"8;
"S \NAC"
BN"4"79;
%"TAP"
"6","(-2950,5275)","2","standard","I228";
;
CDS_LIB"standard"
BOM_COST"IO_SLOT"
ROOM"RISER1"
BODY_TYPE"PLUMBING"
HDL_TAP"TRUE";
"B \NAC \NWC"4;
"S \NAC"
BN"5"86;
%"TAP"
"6","(-2950,5375)","2","standard","I229";
;
CDS_LIB"standard"
BOM_COST"IO_SLOT"
ROOM"RISER1"
BODY_TYPE"PLUMBING"
HDL_TAP"TRUE";
"B \NAC \NWC"4;
"S \NAC"
BN"4"87;
%"TAP"
"6","(-2950,5175)","2","standard","I230";
;
CDS_LIB"standard"
BOM_COST"IO_SLOT"
ROOM"RISER1"
BODY_TYPE"PLUMBING"
HDL_TAP"TRUE";
"B \NAC \NWC"4;
"S \NAC"
BN"6"85;
%"TAP"
"6","(-3100,5125)","2","standard","I231";
;
CDS_LIB"standard"
BOM_COST"IO_SLOT"
ROOM"RISER1"
BODY_TYPE"PLUMBING"
HDL_TAP"TRUE";
"B \NAC \NWC"8;
"S \NAC"
BN"7"76;
%"TAP"
"6","(-3100,5325)","2","standard","I232";
;
CDS_LIB"standard"
BOM_COST"IO_SLOT"
ROOM"RISER1"
BODY_TYPE"PLUMBING"
HDL_TAP"TRUE";
"B \NAC \NWC"8;
"S \NAC"
BN"5"78;
%"TAP"
"6","(-3100,5225)","2","standard","I233";
;
CDS_LIB"standard"
BOM_COST"IO_SLOT"
ROOM"RISER1"
BODY_TYPE"PLUMBING"
HDL_TAP"TRUE";
"B \NAC \NWC"8;
"S \NAC"
BN"6"77;
%"TAP"
"6","(-2950,5075)","2","standard","I234";
;
CDS_LIB"standard"
BOM_COST"IO_SLOT"
ROOM"RISER1"
BODY_TYPE"PLUMBING"
HDL_TAP"TRUE";
"B \NAC \NWC"4;
"S \NAC"
BN"7"84;
%"TAP"
"6","(-2950,4875)","2","standard","I235";
;
CDS_LIB"standard"
BOM_COST"IO_SLOT"
ROOM"RISER1"
BODY_TYPE"PLUMBING"
HDL_TAP"TRUE";
"B \NAC \NWC"4;
"S \NAC"
BN"9"94;
%"TAP"
"6","(-2950,4975)","2","standard","I236";
;
CDS_LIB"standard"
BOM_COST"IO_SLOT"
ROOM"RISER1"
BODY_TYPE"PLUMBING"
HDL_TAP"TRUE";
"B \NAC \NWC"4;
"S \NAC"
BN"8"98;
%"TAP"
"6","(-3100,5025)","2","standard","I237";
;
CDS_LIB"standard"
BOM_COST"IO_SLOT"
ROOM"RISER1"
BODY_TYPE"PLUMBING"
HDL_TAP"TRUE";
"B \NAC \NWC"8;
"S \NAC"
BN"8"75;
%"TAP"
"6","(-3100,4925)","2","standard","I238";
;
CDS_LIB"standard"
BOM_COST"IO_SLOT"
ROOM"RISER1"
BODY_TYPE"PLUMBING"
HDL_TAP"TRUE";
"B \NAC \NWC"8;
"S \NAC"
BN"9"72;
%"TAP"
"6","(-2950,4775)","2","standard","I239";
;
CDS_LIB"standard"
BOM_COST"IO_SLOT"
ROOM"RISER1"
BODY_TYPE"PLUMBING"
HDL_TAP"TRUE";
"B \NAC \NWC"4;
"S \NAC"
BN"10"97;
%"TAP"
"6","(-2950,4675)","2","standard","I240";
;
CDS_LIB"standard"
BOM_COST"IO_SLOT"
ROOM"RISER1"
BODY_TYPE"PLUMBING"
HDL_TAP"TRUE";
"B \NAC \NWC"4;
"S \NAC"
BN"11"93;
%"TAP"
"6","(-3100,4625)","2","standard","I241";
;
CDS_LIB"standard"
BOM_COST"IO_SLOT"
ROOM"RISER1"
BODY_TYPE"PLUMBING"
HDL_TAP"TRUE";
"B \NAC \NWC"8;
"S \NAC"
BN"12"73;
%"TAP"
"6","(-3100,4825)","2","standard","I242";
;
CDS_LIB"standard"
BOM_COST"IO_SLOT"
ROOM"RISER1"
BODY_TYPE"PLUMBING"
HDL_TAP"TRUE";
"B \NAC \NWC"8;
"S \NAC"
BN"10"74;
%"TAP"
"6","(-3100,4725)","2","standard","I243";
;
CDS_LIB"standard"
BOM_COST"IO_SLOT"
ROOM"RISER1"
BODY_TYPE"PLUMBING"
HDL_TAP"TRUE";
"B \NAC \NWC"8;
"S \NAC"
BN"11"71;
%"TAP"
"6","(-2950,4575)","2","standard","I244";
;
CDS_LIB"standard"
BOM_COST"IO_SLOT"
ROOM"RISER1"
BODY_TYPE"PLUMBING"
HDL_TAP"TRUE";
"B \NAC \NWC"4;
"S \NAC"
BN"12"96;
%"TAP"
"6","(-2950,4375)","2","standard","I245";
;
BOM_COST"IO_SLOT"
CDS_LIB"standard"
ROOM"RISER1"
BODY_TYPE"PLUMBING"
HDL_TAP"TRUE";
"B \NAC \NWC"4;
"S \NAC"
BN"14"95;
%"TAP"
"6","(-2950,4475)","2","standard","I246";
;
CDS_LIB"standard"
BOM_COST"IO_SLOT"
ROOM"RISER1"
BODY_TYPE"PLUMBING"
HDL_TAP"TRUE";
"B \NAC \NWC"4;
"S \NAC"
BN"13"92;
%"TAP"
"6","(-3100,4425)","2","standard","I247";
;
CDS_LIB"standard"
BOM_COST"IO_SLOT"
ROOM"RISER1"
BODY_TYPE"PLUMBING"
HDL_TAP"TRUE";
"B \NAC \NWC"8;
"S \NAC"
BN"14"70;
%"TAP"
"6","(-3100,4525)","2","standard","I248";
;
CDS_LIB"standard"
BOM_COST"IO_SLOT"
ROOM"RISER1"
BODY_TYPE"PLUMBING"
HDL_TAP"TRUE";
"B \NAC \NWC"8;
"S \NAC"
BN"13"69;
%"TAP"
"6","(-2950,4275)","2","standard","I249";
;
CDS_LIB"standard"
BOM_COST"IO_SLOT"
ROOM"RISER1"
BODY_TYPE"PLUMBING"
HDL_TAP"TRUE";
"B \NAC \NWC"4;
"S \NAC"
BN"15"119;
%"TAP"
"6","(-3100,4325)","2","standard","I250";
;
CDS_LIB"standard"
BOM_COST"IO_SLOT"
ROOM"RISER1"
BODY_TYPE"PLUMBING"
HDL_TAP"TRUE";
"B \NAC \NWC"8;
"S \NAC"
BN"15"68;
%"TAP"
"6","(-6525,5825)","0","mstr_standard","I251";
;
CDS_LIB"mstr_standard"
BODY_TYPE"PLUMBING"
HDL_TAP"TRUE";
"B \NAC \NWC"6;
"S \NAC"
BN"0"49;
%"TAP"
"6","(-6525,5725)","0","mstr_standard","I252";
;
CDS_LIB"mstr_standard"
BODY_TYPE"PLUMBING"
HDL_TAP"TRUE";
"B \NAC \NWC"6;
"S \NAC"
BN"1"48;
%"TAP"
"6","(-6675,5775)","0","mstr_standard","I253";
;
CDS_LIB"mstr_standard"
BODY_TYPE"PLUMBING"
HDL_TAP"TRUE";
"B \NAC \NWC"5;
"S \NAC"
BN"0"46;
%"TAP"
"6","(-6675,5675)","0","mstr_standard","I254";
;
CDS_LIB"mstr_standard"
BODY_TYPE"PLUMBING"
HDL_TAP"TRUE";
"B \NAC \NWC"5;
"S \NAC"
BN"1"44;
%"TAP"
"6","(-6525,5525)","0","standard","I255";
;
CDS_LIB"standard"
BODY_TYPE"PLUMBING"
HDL_TAP"TRUE";
"B \NAC \NWC"6;
"S \NAC"
BN"3"45;
%"TAP"
"6","(-6525,5625)","0","mstr_standard","I256";
;
CDS_LIB"mstr_standard"
BODY_TYPE"PLUMBING"
HDL_TAP"TRUE";
"B \NAC \NWC"6;
"S \NAC"
BN"2"47;
%"TAP"
"6","(-6525,5425)","0","standard","I257";
;
CDS_LIB"standard"
BODY_TYPE"PLUMBING"
HDL_TAP"TRUE";
"B \NAC \NWC"6;
"S \NAC"
BN"4"43;
%"TAP"
"6","(-6675,5575)","0","standard","I258";
;
CDS_LIB"standard"
BODY_TYPE"PLUMBING"
HDL_TAP"TRUE";
"B \NAC \NWC"5;
"S \NAC"
BN"2"42;
%"TAP"
"6","(-6675,5475)","0","standard","I259";
;
CDS_LIB"standard"
BODY_TYPE"PLUMBING"
HDL_TAP"TRUE";
"B \NAC \NWC"5;
"S \NAC"
BN"3"40;
%"TAP"
"6","(-6525,5325)","0","standard","I260";
;
CDS_LIB"standard"
BODY_TYPE"PLUMBING"
HDL_TAP"TRUE";
"B \NAC \NWC"6;
"S \NAC"
BN"5"41;
%"TAP"
"6","(-6525,5225)","0","standard","I261";
;
CDS_LIB"standard"
BODY_TYPE"PLUMBING"
HDL_TAP"TRUE";
"B \NAC \NWC"6;
"S \NAC"
BN"6"12;
%"TAP"
"6","(-6525,5125)","0","standard","I262";
;
CDS_LIB"standard"
BODY_TYPE"PLUMBING"
HDL_TAP"TRUE";
"B \NAC \NWC"6;
"S \NAC"
BN"7"14;
%"TAP"
"6","(-6675,5275)","0","standard","I263";
;
CDS_LIB"standard"
BODY_TYPE"PLUMBING"
HDL_TAP"TRUE";
"B \NAC \NWC"5;
"S \NAC"
BN"5"11;
%"TAP"
"6","(-6675,5375)","0","standard","I264";
;
CDS_LIB"standard"
BODY_TYPE"PLUMBING"
HDL_TAP"TRUE";
"B \NAC \NWC"5;
"S \NAC"
BN"4"39;
%"TAP"
"6","(-6675,5175)","0","standard","I265";
;
CDS_LIB"standard"
BODY_TYPE"PLUMBING"
HDL_TAP"TRUE";
"B \NAC \NWC"5;
"S \NAC"
BN"6"13;
%"TAP"
"6","(-6525,5025)","0","standard","I266";
;
CDS_LIB"standard"
BODY_TYPE"PLUMBING"
HDL_TAP"TRUE";
"B \NAC \NWC"6;
"S \NAC"
BN"8"16;
%"TAP"
"6","(-6525,4925)","0","standard","I267";
;
CDS_LIB"standard"
BODY_TYPE"PLUMBING"
HDL_TAP"TRUE";
"B \NAC \NWC"6;
"S \NAC"
BN"9"18;
%"TAP"
"6","(-6675,5075)","0","standard","I268";
;
CDS_LIB"standard"
BODY_TYPE"PLUMBING"
HDL_TAP"TRUE";
"B \NAC \NWC"5;
"S \NAC"
BN"7"15;
%"TAP"
"6","(-6675,4975)","0","standard","I269";
;
CDS_LIB"standard"
BODY_TYPE"PLUMBING"
HDL_TAP"TRUE";
"B \NAC \NWC"5;
"S \NAC"
BN"8"17;
%"TAP"
"6","(-6675,4875)","0","standard","I270";
;
CDS_LIB"standard"
BODY_TYPE"PLUMBING"
HDL_TAP"TRUE";
"B \NAC \NWC"5;
"S \NAC"
BN"9"19;
%"TAP"
"6","(-6525,4825)","0","standard","I271";
;
CDS_LIB"standard"
BODY_TYPE"PLUMBING"
HDL_TAP"TRUE";
"B \NAC \NWC"6;
"S \NAC"
BN"10"117;
%"TAP"
"6","(-6525,4625)","0","standard","I272";
;
CDS_LIB"standard"
BODY_TYPE"PLUMBING"
HDL_TAP"TRUE";
"B \NAC \NWC"6;
"S \NAC"
BN"12"22;
%"TAP"
"6","(-6525,4725)","0","standard","I273";
;
CDS_LIB"standard"
BODY_TYPE"PLUMBING"
HDL_TAP"TRUE";
"B \NAC \NWC"6;
"S \NAC"
BN"11"20;
%"TAP"
"6","(-6675,4775)","0","standard","I274";
;
CDS_LIB"standard"
BODY_TYPE"PLUMBING"
HDL_TAP"TRUE";
"B \NAC \NWC"5;
"S \NAC"
BN"10"118;
%"TAP"
"6","(-6675,4675)","0","standard","I275";
;
CDS_LIB"standard"
BODY_TYPE"PLUMBING"
HDL_TAP"TRUE";
"B \NAC \NWC"5;
"S \NAC"
BN"11"21;
%"TAP"
"6","(-6525,4525)","0","standard","I276";
;
CDS_LIB"standard"
BODY_TYPE"PLUMBING"
HDL_TAP"TRUE";
"B \NAC \NWC"6;
"S \NAC"
BN"13"24;
%"TAP"
"6","(-6525,4425)","0","standard","I277";
;
CDS_LIB"standard"
BODY_TYPE"PLUMBING"
HDL_TAP"TRUE";
"B \NAC \NWC"6;
"S \NAC"
BN"14"54;
%"TAP"
"6","(-6675,4575)","0","standard","I278";
;
CDS_LIB"standard"
BODY_TYPE"PLUMBING"
HDL_TAP"TRUE";
"B \NAC \NWC"5;
"S \NAC"
BN"12"23;
%"TAP"
"6","(-6675,4475)","0","standard","I279";
;
CDS_LIB"standard"
BODY_TYPE"PLUMBING"
HDL_TAP"TRUE";
"B \NAC \NWC"5;
"S \NAC"
BN"13"52;
%"TAP"
"6","(-6675,4375)","0","standard","I280";
;
CDS_LIB"standard"
BODY_TYPE"PLUMBING"
HDL_TAP"TRUE";
"B \NAC \NWC"5;
"S \NAC"
BN"14"53;
%"TAP"
"6","(-6525,4325)","0","standard","I281";
;
CDS_LIB"standard"
BODY_TYPE"PLUMBING"
HDL_TAP"TRUE";
"B \NAC \NWC"6;
"S \NAC"
BN"15"51;
%"TAP"
"6","(-6675,4275)","0","standard","I282";
;
CDS_LIB"standard"
BODY_TYPE"PLUMBING"
HDL_TAP"TRUE";
"B \NAC \NWC"5;
"S \NAC"
BN"15"50;
%"TAP"
"6","(-3075,2650)","2","standard","I285";
;
CDS_LIB"standard"
BOM_COST"IO_SLOT"
ROOM"RISER1"
BODY_TYPE"PLUMBING"
HDL_TAP"TRUE";
"B \NAC \NWC"1;
"S \NAC"
BN"3"10;
%"TAP"
"6","(-2925,2600)","2","standard","I286";
;
CDS_LIB"standard"
BOM_COST"IO_SLOT"
ROOM"RISER1"
BODY_TYPE"PLUMBING"
HDL_TAP"TRUE";
"B \NAC \NWC"2;
"S \NAC"
BN"3"133;
%"TAP"
"6","(-2925,2500)","2","standard","I287";
;
CDS_LIB"standard"
BOM_COST"IO_SLOT"
ROOM"RISER1"
BODY_TYPE"PLUMBING"
HDL_TAP"TRUE";
"B \NAC \NWC"2;
"S \NAC"
BN"4"131;
%"TAP"
"6","(-2925,2400)","2","standard","I288";
;
CDS_LIB"standard"
BOM_COST"IO_SLOT"
ROOM"RISER1"
BODY_TYPE"PLUMBING"
HDL_TAP"TRUE";
"B \NAC \NWC"2;
"S \NAC"
BN"5"129;
%"TAP"
"6","(-2925,2300)","2","standard","I289";
;
CDS_LIB"standard"
BOM_COST"IO_SLOT"
ROOM"RISER1"
BODY_TYPE"PLUMBING"
HDL_TAP"TRUE";
"B \NAC \NWC"2;
"S \NAC"
BN"6"127;
%"TAP"
"6","(-2925,2900)","2","mstr_standard","I292";
;
BOM_COST"IO_SLOT"
CDS_LIB"mstr_standard"
ROOM"RISER1"
BODY_TYPE"PLUMBING"
HDL_TAP"TRUE";
"B \NAC \NWC"2;
"S \NAC"
BN"0"135;
%"TAP"
"6","(-3075,2850)","2","mstr_standard","I293";
;
CDS_LIB"mstr_standard"
BOM_COST"IO_SLOT"
ROOM"RISER1"
BODY_TYPE"PLUMBING"
HDL_TAP"TRUE";
"B \NAC \NWC"1;
"S \NAC"
BN"1"116;
%"TAP"
"6","(-3075,2950)","2","mstr_standard","I294";
;
CDS_LIB"mstr_standard"
BOM_COST"IO_SLOT"
ROOM"RISER1"
BODY_TYPE"PLUMBING"
HDL_TAP"TRUE";
"B \NAC \NWC"1;
"S \NAC"
BN"0"136;
%"TAP"
"6","(-2925,2700)","2","standard","I295";
;
CDS_LIB"standard"
BOM_COST"IO_SLOT"
ROOM"RISER1"
BODY_TYPE"PLUMBING"
HDL_TAP"TRUE";
"B \NAC \NWC"2;
"S \NAC"
BN"2"9;
%"TAP"
"6","(-2925,2800)","2","mstr_standard","I296";
;
CDS_LIB"mstr_standard"
BOM_COST"IO_SLOT"
ROOM"RISER1"
BODY_TYPE"PLUMBING"
HDL_TAP"TRUE";
"B \NAC \NWC"2;
"S \NAC"
BN"1"134;
%"TAP"
"6","(-3075,2750)","2","standard","I297";
;
CDS_LIB"standard"
BOM_COST"IO_SLOT"
ROOM"RISER1"
BODY_TYPE"PLUMBING"
HDL_TAP"TRUE";
"B \NAC \NWC"1;
"S \NAC"
BN"2"122;
%"TAP"
"6","(-3075,2350)","2","standard","I298";
;
CDS_LIB"standard"
BOM_COST"IO_SLOT"
ROOM"RISER1"
BODY_TYPE"PLUMBING"
HDL_TAP"TRUE";
"B \NAC \NWC"1;
"S \NAC"
BN"6"130;
%"TAP"
"6","(-3075,2550)","2","standard","I299";
;
CDS_LIB"standard"
BOM_COST"IO_SLOT"
ROOM"RISER1"
BODY_TYPE"PLUMBING"
HDL_TAP"TRUE";
"B \NAC \NWC"1;
"S \NAC"
BN"4"132;
%"TAP"
"6","(-3075,2450)","2","standard","I300";
;
CDS_LIB"standard"
BOM_COST"IO_SLOT"
ROOM"RISER1"
BODY_TYPE"PLUMBING"
HDL_TAP"TRUE";
"B \NAC \NWC"1;
"S \NAC"
BN"5"128;
%"TAP"
"6","(-2925,2200)","2","standard","I301";
;
CDS_LIB"standard"
BOM_COST"IO_SLOT"
ROOM"RISER1"
BODY_TYPE"PLUMBING"
HDL_TAP"TRUE";
"B \NAC \NWC"2;
"S \NAC"
BN"7"123;
%"TAP"
"6","(-2925,2100)","2","standard","I302";
;
CDS_LIB"standard"
BOM_COST"IO_SLOT"
ROOM"RISER1"
BODY_TYPE"PLUMBING"
HDL_TAP"TRUE";
"B \NAC \NWC"2;
"S \NAC"
BN"8"67;
%"TAP"
"6","(-3075,2250)","2","standard","I303";
;
CDS_LIB"standard"
BOM_COST"IO_SLOT"
ROOM"RISER1"
BODY_TYPE"PLUMBING"
HDL_TAP"TRUE";
"B \NAC \NWC"1;
"S \NAC"
BN"7"121;
%"TAP"
"6","(-3075,2150)","2","standard","I304";
;
CDS_LIB"standard"
BOM_COST"IO_SLOT"
ROOM"RISER1"
BODY_TYPE"PLUMBING"
HDL_TAP"TRUE";
"B \NAC \NWC"1;
"S \NAC"
BN"8"66;
%"TAP"
"6","(-3075,2050)","2","standard","I305";
;
CDS_LIB"standard"
BOM_COST"IO_SLOT"
ROOM"RISER1"
BODY_TYPE"PLUMBING"
HDL_TAP"TRUE";
"B \NAC \NWC"1;
"S \NAC"
BN"9"120;
%"TAP"
"6","(-2925,2000)","2","standard","I306";
;
CDS_LIB"standard"
BOM_COST"IO_SLOT"
ROOM"RISER1"
BODY_TYPE"PLUMBING"
HDL_TAP"TRUE";
"B \NAC \NWC"2;
"S \NAC"
BN"9"60;
%"TAP"
"6","(-2925,1800)","2","standard","I307";
;
CDS_LIB"standard"
BOM_COST"IO_SLOT"
ROOM"RISER1"
BODY_TYPE"PLUMBING"
HDL_TAP"TRUE";
"B \NAC \NWC"2;
"S \NAC"
BN"11"64;
%"TAP"
"6","(-2925,1900)","2","standard","I308";
;
CDS_LIB"standard"
BOM_COST"IO_SLOT"
ROOM"RISER1"
BODY_TYPE"PLUMBING"
HDL_TAP"TRUE";
"B \NAC \NWC"2;
"S \NAC"
BN"10"126;
%"TAP"
"6","(-3075,1950)","2","standard","I309";
;
CDS_LIB"standard"
BOM_COST"IO_SLOT"
ROOM"RISER1"
BODY_TYPE"PLUMBING"
HDL_TAP"TRUE";
"B \NAC \NWC"1;
"S \NAC"
BN"10"125;
%"TAP"
"6","(-3075,1850)","2","standard","I310";
;
CDS_LIB"standard"
BOM_COST"IO_SLOT"
ROOM"RISER1"
BODY_TYPE"PLUMBING"
HDL_TAP"TRUE";
"B \NAC \NWC"1;
"S \NAC"
BN"11"58;
%"TAP"
"6","(-2925,1700)","2","standard","I311";
;
CDS_LIB"standard"
BOM_COST"IO_SLOT"
ROOM"RISER1"
BODY_TYPE"PLUMBING"
HDL_TAP"TRUE";
"B \NAC \NWC"2;
"S \NAC"
BN"12"62;
%"TAP"
"6","(-2925,1600)","2","standard","I312";
;
CDS_LIB"standard"
BOM_COST"IO_SLOT"
ROOM"RISER1"
BODY_TYPE"PLUMBING"
HDL_TAP"TRUE";
"B \NAC \NWC"2;
"S \NAC"
BN"13"61;
%"TAP"
"6","(-3075,1650)","2","standard","I313";
;
CDS_LIB"standard"
BOM_COST"IO_SLOT"
ROOM"RISER1"
BODY_TYPE"PLUMBING"
HDL_TAP"TRUE";
"B \NAC \NWC"1;
"S \NAC"
BN"13"59;
%"TAP"
"6","(-3075,1750)","2","standard","I314";
;
CDS_LIB"standard"
BOM_COST"IO_SLOT"
ROOM"RISER1"
BODY_TYPE"PLUMBING"
HDL_TAP"TRUE";
"B \NAC \NWC"1;
"S \NAC"
BN"12"56;
%"TAP"
"6","(-3075,1550)","2","standard","I315";
;
CDS_LIB"standard"
BOM_COST"IO_SLOT"
ROOM"RISER1"
BODY_TYPE"PLUMBING"
HDL_TAP"TRUE";
"B \NAC \NWC"1;
"S \NAC"
BN"14"57;
%"TAP"
"6","(-2925,1500)","2","standard","I316";
;
BOM_COST"IO_SLOT"
CDS_LIB"standard"
ROOM"RISER1"
BODY_TYPE"PLUMBING"
HDL_TAP"TRUE";
"B \NAC \NWC"2;
"S \NAC"
BN"14"65;
%"TAP"
"6","(-2925,1400)","2","standard","I317";
;
CDS_LIB"standard"
BOM_COST"IO_SLOT"
ROOM"RISER1"
BODY_TYPE"PLUMBING"
HDL_TAP"TRUE";
"B \NAC \NWC"2;
"S \NAC"
BN"15"63;
%"TAP"
"6","(-3075,1450)","2","standard","I318";
;
CDS_LIB"standard"
BOM_COST"IO_SLOT"
ROOM"RISER1"
BODY_TYPE"PLUMBING"
HDL_TAP"TRUE";
"B \NAC \NWC"1;
"S \NAC"
BN"15"55;
%"TAP"
"6","(-6500,2950)","0","mstr_standard","I319";
;
CDS_LIB"mstr_standard"
BODY_TYPE"PLUMBING"
HDL_TAP"TRUE";
"B \NAC \NWC"3;
"S \NAC"
BN"0"111;
%"TAP"
"6","(-6500,2850)","0","mstr_standard","I320";
;
CDS_LIB"mstr_standard"
BODY_TYPE"PLUMBING"
HDL_TAP"TRUE";
"B \NAC \NWC"3;
"S \NAC"
BN"1"103;
%"TAP"
"6","(-6650,2900)","0","mstr_standard","I321";
;
CDS_LIB"mstr_standard"
BODY_TYPE"PLUMBING"
HDL_TAP"TRUE";
"B \NAC \NWC"7;
"S \NAC"
BN"0"102;
%"TAP"
"6","(-6500,2750)","0","mstr_standard","I322";
;
CDS_LIB"mstr_standard"
BODY_TYPE"PLUMBING"
HDL_TAP"TRUE";
"B \NAC \NWC"3;
"S \NAC"
BN"2"105;
%"TAP"
"6","(-6500,2650)","0","standard","I323";
;
CDS_LIB"standard"
BODY_TYPE"PLUMBING"
HDL_TAP"TRUE";
"B \NAC \NWC"3;
"S \NAC"
BN"3"107;
%"TAP"
"6","(-6650,2800)","0","mstr_standard","I324";
;
CDS_LIB"mstr_standard"
BODY_TYPE"PLUMBING"
HDL_TAP"TRUE";
"B \NAC \NWC"7;
"S \NAC"
BN"1"104;
%"TAP"
"6","(-6650,2700)","0","standard","I325";
;
CDS_LIB"standard"
BODY_TYPE"PLUMBING"
HDL_TAP"TRUE";
"B \NAC \NWC"7;
"S \NAC"
BN"2"106;
%"TAP"
"6","(-6650,2600)","0","standard","I326";
;
CDS_LIB"standard"
BODY_TYPE"PLUMBING"
HDL_TAP"TRUE";
"B \NAC \NWC"7;
"S \NAC"
BN"3"108;
%"TAP"
"6","(-6500,2550)","0","standard","I327";
;
CDS_LIB"standard"
BODY_TYPE"PLUMBING"
HDL_TAP"TRUE";
"B \NAC \NWC"3;
"S \NAC"
BN"4"113;
%"TAP"
"6","(-6500,2450)","0","standard","I328";
;
CDS_LIB"standard"
BODY_TYPE"PLUMBING"
HDL_TAP"TRUE";
"B \NAC \NWC"3;
"S \NAC"
BN"5"115;
%"TAP"
"6","(-6500,2350)","0","standard","I329";
;
CDS_LIB"standard"
BODY_TYPE"PLUMBING"
HDL_TAP"TRUE";
"B \NAC \NWC"3;
"S \NAC"
BN"6"109;
%"TAP"
"6","(-6650,2500)","0","standard","I330";
;
CDS_LIB"standard"
BODY_TYPE"PLUMBING"
HDL_TAP"TRUE";
"B \NAC \NWC"7;
"S \NAC"
BN"4"114;
%"TAP"
"6","(-6650,2400)","0","standard","I331";
;
CDS_LIB"standard"
BODY_TYPE"PLUMBING"
HDL_TAP"TRUE";
"B \NAC \NWC"7;
"S \NAC"
BN"5"112;
%"TAP"
"6","(-6500,2250)","0","standard","I332";
;
CDS_LIB"standard"
BODY_TYPE"PLUMBING"
HDL_TAP"TRUE";
"B \NAC \NWC"3;
"S \NAC"
BN"7"25;
%"TAP"
"6","(-6500,2150)","0","standard","I333";
;
CDS_LIB"standard"
BODY_TYPE"PLUMBING"
HDL_TAP"TRUE";
"B \NAC \NWC"3;
"S \NAC"
BN"8"124;
%"TAP"
"6","(-6500,2050)","0","standard","I334";
;
CDS_LIB"standard"
BODY_TYPE"PLUMBING"
HDL_TAP"TRUE";
"B \NAC \NWC"3;
"S \NAC"
BN"9"27;
%"TAP"
"6","(-6650,2300)","0","standard","I335";
;
CDS_LIB"standard"
BODY_TYPE"PLUMBING"
HDL_TAP"TRUE";
"B \NAC \NWC"7;
"S \NAC"
BN"6"110;
%"TAP"
"6","(-6650,2200)","0","standard","I336";
;
CDS_LIB"standard"
BODY_TYPE"PLUMBING"
HDL_TAP"TRUE";
"B \NAC \NWC"7;
"S \NAC"
BN"7"26;
%"TAP"
"6","(-6650,2100)","0","standard","I337";
;
CDS_LIB"standard"
BODY_TYPE"PLUMBING"
HDL_TAP"TRUE";
"B \NAC \NWC"7;
"S \NAC"
BN"8"101;
%"TAP"
"6","(-6500,1950)","0","standard","I340";
;
CDS_LIB"standard"
BODY_TYPE"PLUMBING"
HDL_TAP"TRUE";
"B \NAC \NWC"3;
"S \NAC"
BN"10"36;
%"TAP"
"6","(-6500,1850)","0","standard","I341";
;
CDS_LIB"standard"
BODY_TYPE"PLUMBING"
HDL_TAP"TRUE";
"B \NAC \NWC"3;
"S \NAC"
BN"11"38;
%"TAP"
"6","(-6650,2000)","0","standard","I342";
;
CDS_LIB"standard"
BODY_TYPE"PLUMBING"
HDL_TAP"TRUE";
"B \NAC \NWC"7;
"S \NAC"
BN"9"100;
%"TAP"
"6","(-6650,1900)","0","standard","I343";
;
CDS_LIB"standard"
BODY_TYPE"PLUMBING"
HDL_TAP"TRUE";
"B \NAC \NWC"7;
"S \NAC"
BN"10"37;
%"TAP"
"6","(-6650,1800)","0","standard","I344";
;
CDS_LIB"standard"
BODY_TYPE"PLUMBING"
HDL_TAP"TRUE";
"B \NAC \NWC"7;
"S \NAC"
BN"11"99;
%"TAP"
"6","(-6500,1650)","0","standard","I345";
;
CDS_LIB"standard"
BODY_TYPE"PLUMBING"
HDL_TAP"TRUE";
"B \NAC \NWC"3;
"S \NAC"
BN"13"29;
%"TAP"
"6","(-6500,1750)","0","standard","I346";
;
CDS_LIB"standard"
BODY_TYPE"PLUMBING"
HDL_TAP"TRUE";
"B \NAC \NWC"3;
"S \NAC"
BN"12"28;
%"TAP"
"6","(-6500,1550)","0","standard","I347";
;
CDS_LIB"standard"
BODY_TYPE"PLUMBING"
HDL_TAP"TRUE";
"B \NAC \NWC"3;
"S \NAC"
BN"14"32;
%"TAP"
"6","(-6650,1700)","0","standard","I348";
;
CDS_LIB"standard"
BODY_TYPE"PLUMBING"
HDL_TAP"TRUE";
"B \NAC \NWC"7;
"S \NAC"
BN"12"30;
%"TAP"
"6","(-6650,1600)","0","standard","I349";
;
CDS_LIB"standard"
BODY_TYPE"PLUMBING"
HDL_TAP"TRUE";
"B \NAC \NWC"7;
"S \NAC"
BN"13"31;
%"TAP"
"6","(-6500,1450)","0","standard","I350";
;
CDS_LIB"standard"
BODY_TYPE"PLUMBING"
HDL_TAP"TRUE";
"B \NAC \NWC"3;
"S \NAC"
BN"15"34;
%"TAP"
"6","(-6650,1500)","0","standard","I351";
;
CDS_LIB"standard"
BODY_TYPE"PLUMBING"
HDL_TAP"TRUE";
"B \NAC \NWC"7;
"S \NAC"
BN"14"33;
%"TAP"
"6","(-6650,1400)","0","standard","I352";
;
CDS_LIB"standard"
BODY_TYPE"PLUMBING"
HDL_TAP"TRUE";
"B \NAC \NWC"7;
"S \NAC"
BN"15"35;
END.
